(kicad_pcb
	(version 20260206)
	(generator "pcbnew")
	(generator_version "10.0")
	(general
		(thickness 1.6)
		(legacy_teardrops no)
	)
	(paper "A4")
	(title_block
		(title "Bryce Canyon_SCC_16316-1_OCP.brd")
		(comment 1 "Bryce Canyon / footprint 64 of 1561 (U1), pads 699-818 of 1020")
	)
	(layers
		(0 "F.Cu" signal "TOP")
		(4 "In1.Cu" signal "L2GND")
		(6 "In2.Cu" signal "L3")
		(8 "In3.Cu" signal "L4VCC")
		(10 "In4.Cu" signal "L5VCC")
		(12 "In5.Cu" signal "L6")
		(14 "In6.Cu" signal "L7GND")
		(2 "B.Cu" signal "BOTTOM")
		(9 "F.Adhes" user "F.Adhesive")
		(11 "B.Adhes" user "B.Adhesive")
		(13 "F.Paste" user "Package Geometry/Pastemask Top")
		(15 "B.Paste" user "Package Geometry/Pastemask Bottom")
		(5 "F.SilkS" user "Ref Des/Silkscreen Top")
		(7 "B.SilkS" user "Ref Des/Silkscreen Bottom")
		(1 "F.Mask" user "Board Geometry/Soldermask Top")
		(3 "B.Mask" user "Board Geometry/Soldermask Bottom")
		(17 "Dwgs.User" user "User.Drawings")
		(19 "Cmts.User" user "User.Comments")
		(21 "Eco1.User" user "User.Eco1")
		(23 "Eco2.User" user "User.Eco2")
		(25 "Edge.Cuts" user "Board Geometry/Outline")
		(27 "Margin" user)
		(31 "F.CrtYd" user "Package Geometry/Place Bound Top")
		(29 "B.CrtYd" user "Package Geometry/Place Bound Bottom")
		(35 "F.Fab" user "Ref Des/Assembly Top")
		(33 "B.Fab" user "Ref Des/Assembly Bottom")
	)
	(footprint ""
		(layer "F.Cu")
		(at 115.000024 -67.00012)
		(property "Reference" "U1"
			(at 0 0 0)
			(layer "F.SilkS")
			(hide yes)
			(effects
				(font
					(size 1.27 1.27)
				)
			)
		)
		(property "Value" "LSISAS3X48-GP"
			(at -24.358092 -5.0292 0)
			(unlocked yes)
			(layer "F.Fab")
			(hide yes)
			(effects
				(font
					(size 1.016 1.016)
					(thickness 0.1524)
				)
			)
		)
		(property "Device Type" "BGA1020C33H83"
			(at -24.358092 -6.5532 0)
			(unlocked yes)
			(layer "F.Fab")
			(hide yes)
			(effects
				(font
					(size 1.016 1.016)
					(thickness 0.1524)
				)
			)
		)
		(duplicate_pad_numbers_are_jumpers no)
		(pad "K31" smd circle
			(at 14.500098 -6.500114)
			(size 0.4572 0.4572)
			(layers "F.Cu" "F.Mask" "F.Paste")
			(net "PHY_EXP_TO_CONN_C_8_DP")
		)
		(pad "K32" smd circle
			(at 15.500096 -6.500114)
			(size 0.4572 0.4572)
			(layers "F.Cu" "F.Mask" "F.Paste")
			(net "GND")
		)
		(pad "L1" smd circle
			(at -15.500096 -5.500116)
			(size 0.4572 0.4572)
			(layers "F.Cu" "F.Mask" "F.Paste")
			(net "Net_1273")
		)
		(pad "L2" smd circle
			(at -14.500098 -5.500116)
			(size 0.4572 0.4572)
			(layers "F.Cu" "F.Mask" "F.Paste")
			(net "Net_1272")
		)
		(pad "L3" smd circle
			(at -13.5001 -5.500116)
			(size 0.4572 0.4572)
			(layers "F.Cu" "F.Mask" "F.Paste")
			(net "GND")
		)
		(pad "L4" smd circle
			(at -12.500102 -5.500116)
			(size 0.4572 0.4572)
			(layers "F.Cu" "F.Mask" "F.Paste")
			(net "Net_1271")
		)
		(pad "L5" smd circle
			(at -11.500104 -5.500116)
			(size 0.4572 0.4572)
			(layers "F.Cu" "F.Mask" "F.Paste")
			(net "GND")
		)
		(pad "L6" smd circle
			(at -10.500106 -5.500116)
			(size 0.4572 0.4572)
			(layers "F.Cu" "F.Mask" "F.Paste")
			(net "Net_1231")
		)
		(pad "L7" smd circle
			(at -9.500108 -5.500116)
			(size 0.4572 0.4572)
			(layers "F.Cu" "F.Mask" "F.Paste")
			(net "Net_1230")
		)
		(pad "L8" smd circle
			(at -8.50011 -5.500116)
			(size 0.4572 0.4572)
			(layers "F.Cu" "F.Mask" "F.Paste")
			(net "Net_1229")
		)
		(pad "L9" smd circle
			(at -7.500112 -5.500116)
			(size 0.4572 0.4572)
			(layers "F.Cu" "F.Mask" "F.Paste")
			(net "GND")
		)
		(pad "L10" smd circle
			(at -6.500114 -5.500116)
			(size 0.4572 0.4572)
			(layers "F.Cu" "F.Mask" "F.Paste")
			(net "P1V8_E")
		)
		(pad "L11" smd circle
			(at -5.500116 -5.500116)
			(size 0.4572 0.4572)
			(layers "F.Cu" "F.Mask" "F.Paste")
			(net "DRIVE_3_ACT")
		)
		(pad "L12" smd circle
			(at -4.500118 -5.500116)
			(size 0.4572 0.4572)
			(layers "F.Cu" "F.Mask" "F.Paste")
			(net "LSI_SCAN_ENABLE")
		)
		(pad "L13" smd circle
			(at -3.50012 -5.500116)
			(size 0.4572 0.4572)
			(layers "F.Cu" "F.Mask" "F.Paste")
			(net "P1V8_E")
		)
		(pad "L14" smd circle
			(at -2.500122 -5.500116)
			(size 0.4572 0.4572)
			(layers "F.Cu" "F.Mask" "F.Paste")
			(net "XM_DATA4")
		)
		(pad "L15" smd circle
			(at -1.500124 -5.500116)
			(size 0.4572 0.4572)
			(layers "F.Cu" "F.Mask" "F.Paste")
			(net "P1V8_E")
		)
		(pad "L16" smd circle
			(at -0.500126 -5.500116)
			(size 0.4572 0.4572)
			(layers "F.Cu" "F.Mask" "F.Paste")
			(net "EXP_XM_ADDR_10")
		)
		(pad "L17" smd circle
			(at 0.500126 -5.500116)
			(size 0.4572 0.4572)
			(layers "F.Cu" "F.Mask" "F.Paste")
			(net "P1V8_E")
		)
		(pad "L18" smd circle
			(at 1.500124 -5.500116)
			(size 0.4572 0.4572)
			(layers "F.Cu" "F.Mask" "F.Paste")
			(net "Net_1219")
		)
		(pad "L19" smd circle
			(at 2.500122 -5.500116)
			(size 0.4572 0.4572)
			(layers "F.Cu" "F.Mask" "F.Paste")
			(net "P1V8_E")
		)
		(pad "L20" smd circle
			(at 3.50012 -5.500116)
			(size 0.4572 0.4572)
			(layers "F.Cu" "F.Mask" "F.Paste")
			(net "LSI_EFUSE")
		)
		(pad "L21" smd circle
			(at 4.500118 -5.500116)
			(size 0.4572 0.4572)
			(layers "F.Cu" "F.Mask" "F.Paste")
			(net "P1V8_E")
		)
		(pad "L22" smd circle
			(at 5.500116 -5.500116)
			(size 0.4572 0.4572)
			(layers "F.Cu" "F.Mask" "F.Paste")
			(net "EXP_I2C_SDA9")
		)
		(pad "L23" smd circle
			(at 6.500114 -5.500116)
			(size 0.4572 0.4572)
			(layers "F.Cu" "F.Mask" "F.Paste")
			(net "P1V8_E")
		)
		(pad "L24" smd circle
			(at 7.500112 -5.500116)
			(size 0.4572 0.4572)
			(layers "F.Cu" "F.Mask" "F.Paste")
			(net "I2C_SCC_SCL2_LS")
		)
		(pad "L25" smd circle
			(at 8.50011 -5.500116)
			(size 0.4572 0.4572)
			(layers "F.Cu" "F.Mask" "F.Paste")
			(net "GND")
		)
		(pad "L26" smd circle
			(at 9.500108 -5.500116)
			(size 0.4572 0.4572)
			(layers "F.Cu" "F.Mask" "F.Paste")
			(net "GB_VDDA")
		)
		(pad "L27" smd circle
			(at 10.500106 -5.500116)
			(size 0.4572 0.4572)
			(layers "F.Cu" "F.Mask" "F.Paste")
			(net "PHY_DPB_TO_SCC_C_7_DN")
		)
		(pad "L28" smd circle
			(at 11.500104 -5.500116)
			(size 0.4572 0.4572)
			(layers "F.Cu" "F.Mask" "F.Paste")
			(net "PHY_DPB_TO_SCC_C_7_DP")
		)
		(pad "L29" smd circle
			(at 12.500102 -5.500116)
			(size 0.4572 0.4572)
			(layers "F.Cu" "F.Mask" "F.Paste")
			(net "GND")
		)
		(pad "L30" smd circle
			(at 13.5001 -5.500116)
			(size 0.4572 0.4572)
			(layers "F.Cu" "F.Mask" "F.Paste")
			(net "GB_VDDA")
		)
		(pad "L31" smd circle
			(at 14.500098 -5.500116)
			(size 0.4572 0.4572)
			(layers "F.Cu" "F.Mask" "F.Paste")
			(net "PHY_SCC_TO_DPB_7_DN")
		)
		(pad "L32" smd circle
			(at 15.500096 -5.500116)
			(size 0.4572 0.4572)
			(layers "F.Cu" "F.Mask" "F.Paste")
			(net "PHY_SCC_TO_DPB_7_DP")
		)
		(pad "M1" smd circle
			(at -15.500096 -4.500118)
			(size 0.4572 0.4572)
			(layers "F.Cu" "F.Mask" "F.Paste")
			(net "Net_1270")
		)
		(pad "M2" smd circle
			(at -14.500098 -4.500118)
			(size 0.4572 0.4572)
			(layers "F.Cu" "F.Mask" "F.Paste")
			(net "VDDIO_DDR")
		)
		(pad "M3" smd circle
			(at -13.5001 -4.500118)
			(size 0.4572 0.4572)
			(layers "F.Cu" "F.Mask" "F.Paste")
			(net "Net_1269")
		)
		(pad "M4" smd circle
			(at -12.500102 -4.500118)
			(size 0.4572 0.4572)
			(layers "F.Cu" "F.Mask" "F.Paste")
			(net "VDDIO_DDR")
		)
		(pad "M5" smd circle
			(at -11.500104 -4.500118)
			(size 0.4572 0.4572)
			(layers "F.Cu" "F.Mask" "F.Paste")
			(net "Net_1268")
		)
		(pad "M6" smd circle
			(at -10.500106 -4.500118)
			(size 0.4572 0.4572)
			(layers "F.Cu" "F.Mask" "F.Paste")
			(net "VDDIO_DDR")
		)
		(pad "M7" smd circle
			(at -9.500108 -4.500118)
			(size 0.4572 0.4572)
			(layers "F.Cu" "F.Mask" "F.Paste")
			(net "VDDIO_DDR")
		)
		(pad "M8" smd circle
			(at -8.50011 -4.500118)
			(size 0.4572 0.4572)
			(layers "F.Cu" "F.Mask" "F.Paste")
			(net "GND")
		)
		(pad "M9" smd circle
			(at -7.500112 -4.500118)
			(size 0.4572 0.4572)
			(layers "F.Cu" "F.Mask" "F.Paste")
			(net "VDDIO_DDR")
		)
		(pad "M10" smd circle
			(at -6.500114 -4.500118)
			(size 0.4572 0.4572)
			(layers "F.Cu" "F.Mask" "F.Paste")
			(net "GND")
		)
		(pad "M11" smd circle
			(at -5.500116 -4.500118)
			(size 0.4572 0.4572)
			(layers "F.Cu" "F.Mask" "F.Paste")
			(net "GND")
		)
		(pad "M12" smd circle
			(at -4.500118 -4.500118)
			(size 0.4572 0.4572)
			(layers "F.Cu" "F.Mask" "F.Paste")
			(net "P1V8_E")
		)
		(pad "M13" smd circle
			(at -3.50012 -4.500118)
			(size 0.4572 0.4572)
			(layers "F.Cu" "F.Mask" "F.Paste")
			(net "GND")
		)
		(pad "M14" smd circle
			(at -2.500122 -4.500118)
			(size 0.4572 0.4572)
			(layers "F.Cu" "F.Mask" "F.Paste")
			(net "P1V8_E")
		)
		(pad "M15" smd circle
			(at -1.500124 -4.500118)
			(size 0.4572 0.4572)
			(layers "F.Cu" "F.Mask" "F.Paste")
			(net "GND")
		)
		(pad "M16" smd circle
			(at -0.500126 -4.500118)
			(size 0.4572 0.4572)
			(layers "F.Cu" "F.Mask" "F.Paste")
			(net "P1V8_E")
		)
		(pad "M17" smd circle
			(at 0.500126 -4.500118)
			(size 0.4572 0.4572)
			(layers "F.Cu" "F.Mask" "F.Paste")
			(net "GND")
		)
		(pad "M18" smd circle
			(at 1.500124 -4.500118)
			(size 0.4572 0.4572)
			(layers "F.Cu" "F.Mask" "F.Paste")
			(net "P1V8_E")
		)
		(pad "M19" smd circle
			(at 2.500122 -4.500118)
			(size 0.4572 0.4572)
			(layers "F.Cu" "F.Mask" "F.Paste")
			(net "GND")
		)
		(pad "M20" smd circle
			(at 3.50012 -4.500118)
			(size 0.4572 0.4572)
			(layers "F.Cu" "F.Mask" "F.Paste")
			(net "P1V8_E")
		)
		(pad "M21" smd circle
			(at 4.500118 -4.500118)
			(size 0.4572 0.4572)
			(layers "F.Cu" "F.Mask" "F.Paste")
			(net "GND")
		)
		(pad "M22" smd circle
			(at 5.500116 -4.500118)
			(size 0.4572 0.4572)
			(layers "F.Cu" "F.Mask" "F.Paste")
			(net "GND")
		)
		(pad "M23" smd circle
			(at 6.500114 -4.500118)
			(size 0.4572 0.4572)
			(layers "F.Cu" "F.Mask" "F.Paste")
			(net "GND")
		)
		(pad "M24" smd circle
			(at 7.500112 -4.500118)
			(size 0.4572 0.4572)
			(layers "F.Cu" "F.Mask" "F.Paste")
			(net "GND")
		)
		(pad "M25" smd circle
			(at 8.50011 -4.500118)
			(size 0.4572 0.4572)
			(layers "F.Cu" "F.Mask" "F.Paste")
			(net "GB_VDDA")
		)
		(pad "M26" smd circle
			(at 9.500108 -4.500118)
			(size 0.4572 0.4572)
			(layers "F.Cu" "F.Mask" "F.Paste")
			(net "GND")
		)
		(pad "M27" smd circle
			(at 10.500106 -4.500118)
			(size 0.4572 0.4572)
			(layers "F.Cu" "F.Mask" "F.Paste")
			(net "PHY_DPB_TO_SCC_C_6_DN")
		)
		(pad "M28" smd circle
			(at 11.500104 -4.500118)
			(size 0.4572 0.4572)
			(layers "F.Cu" "F.Mask" "F.Paste")
			(net "PHY_DPB_TO_SCC_C_6_DP")
		)
		(pad "M29" smd circle
			(at 12.500102 -4.500118)
			(size 0.4572 0.4572)
			(layers "F.Cu" "F.Mask" "F.Paste")
			(net "GB_VDDA")
		)
		(pad "M30" smd circle
			(at 13.5001 -4.500118)
			(size 0.4572 0.4572)
			(layers "F.Cu" "F.Mask" "F.Paste")
			(net "PHY_SCC_TO_DPB_6_DN")
		)
		(pad "M31" smd circle
			(at 14.500098 -4.500118)
			(size 0.4572 0.4572)
			(layers "F.Cu" "F.Mask" "F.Paste")
			(net "PHY_SCC_TO_DPB_6_DP")
		)
		(pad "M32" smd circle
			(at 15.500096 -4.500118)
			(size 0.4572 0.4572)
			(layers "F.Cu" "F.Mask" "F.Paste")
			(net "GND")
		)
		(pad "N1" smd circle
			(at -15.500096 -3.50012)
			(size 0.4572 0.4572)
			(layers "F.Cu" "F.Mask" "F.Paste")
			(net "Net_1267")
		)
		(pad "N2" smd circle
			(at -14.500098 -3.50012)
			(size 0.4572 0.4572)
			(layers "F.Cu" "F.Mask" "F.Paste")
			(net "Net_1266")
		)
		(pad "N3" smd circle
			(at -13.5001 -3.50012)
			(size 0.4572 0.4572)
			(layers "F.Cu" "F.Mask" "F.Paste")
			(net "GND")
		)
		(pad "N4" smd circle
			(at -12.500102 -3.50012)
			(size 0.4572 0.4572)
			(layers "F.Cu" "F.Mask" "F.Paste")
			(net "Net_1265")
		)
		(pad "N5" smd circle
			(at -11.500104 -3.50012)
			(size 0.4572 0.4572)
			(layers "F.Cu" "F.Mask" "F.Paste")
			(net "GND")
		)
		(pad "N6" smd circle
			(at -10.500106 -3.50012)
			(size 0.4572 0.4572)
			(layers "F.Cu" "F.Mask" "F.Paste")
			(net "Net_1228")
		)
		(pad "N7" smd circle
			(at -9.500108 -3.50012)
			(size 0.4572 0.4572)
			(layers "F.Cu" "F.Mask" "F.Paste")
			(net "GND")
		)
		(pad "N8" smd circle
			(at -8.50011 -3.50012)
			(size 0.4572 0.4572)
			(layers "F.Cu" "F.Mask" "F.Paste")
			(net "VDDIO_DDR")
		)
		(pad "N9" smd circle
			(at -7.500112 -3.50012)
			(size 0.4572 0.4572)
			(layers "F.Cu" "F.Mask" "F.Paste")
			(net "GND")
		)
		(pad "N10" smd circle
			(at -6.500114 -3.50012)
			(size 0.4572 0.4572)
			(layers "F.Cu" "F.Mask" "F.Paste")
			(net "VDDIO_DDR")
		)
		(pad "N11" smd circle
			(at -5.500116 -3.50012)
			(size 0.4572 0.4572)
			(layers "F.Cu" "F.Mask" "F.Paste")
			(net "GND")
		)
		(pad "N12" smd circle
			(at -4.500118 -3.50012)
			(size 0.4572 0.4572)
			(layers "F.Cu" "F.Mask" "F.Paste")
			(net "P0V9")
		)
		(pad "N13" smd circle
			(at -3.50012 -3.50012)
			(size 0.4572 0.4572)
			(layers "F.Cu" "F.Mask" "F.Paste")
			(net "GND")
		)
		(pad "N14" smd circle
			(at -2.500122 -3.50012)
			(size 0.4572 0.4572)
			(layers "F.Cu" "F.Mask" "F.Paste")
			(net "P0V9")
		)
		(pad "N15" smd circle
			(at -1.500124 -3.50012)
			(size 0.4572 0.4572)
			(layers "F.Cu" "F.Mask" "F.Paste")
			(net "GND")
		)
		(pad "N16" smd circle
			(at -0.500126 -3.50012)
			(size 0.4572 0.4572)
			(layers "F.Cu" "F.Mask" "F.Paste")
			(net "P0V9")
		)
		(pad "N17" smd circle
			(at 0.500126 -3.50012)
			(size 0.4572 0.4572)
			(layers "F.Cu" "F.Mask" "F.Paste")
			(net "GND")
		)
		(pad "N18" smd circle
			(at 1.500124 -3.50012)
			(size 0.4572 0.4572)
			(layers "F.Cu" "F.Mask" "F.Paste")
			(net "P0V9")
		)
		(pad "N19" smd circle
			(at 2.500122 -3.50012)
			(size 0.4572 0.4572)
			(layers "F.Cu" "F.Mask" "F.Paste")
			(net "GND")
		)
		(pad "N20" smd circle
			(at 3.50012 -3.50012)
			(size 0.4572 0.4572)
			(layers "F.Cu" "F.Mask" "F.Paste")
			(net "P0V9")
		)
		(pad "N21" smd circle
			(at 4.500118 -3.50012)
			(size 0.4572 0.4572)
			(layers "F.Cu" "F.Mask" "F.Paste")
			(net "GND")
		)
		(pad "N22" smd circle
			(at 5.500116 -3.50012)
			(size 0.4572 0.4572)
			(layers "F.Cu" "F.Mask" "F.Paste")
			(net "GB_VDDH")
		)
		(pad "N23" smd circle
			(at 6.500114 -3.50012)
			(size 0.4572 0.4572)
			(layers "F.Cu" "F.Mask" "F.Paste")
			(net "GND")
		)
		(pad "N24" smd circle
			(at 7.500112 -3.50012)
			(size 0.4572 0.4572)
			(layers "F.Cu" "F.Mask" "F.Paste")
			(net "GB_VDDA")
		)
		(pad "N25" smd circle
			(at 8.50011 -3.50012)
			(size 0.4572 0.4572)
			(layers "F.Cu" "F.Mask" "F.Paste")
			(net "GND")
		)
		(pad "N26" smd circle
			(at 9.500108 -3.50012)
			(size 0.4572 0.4572)
			(layers "F.Cu" "F.Mask" "F.Paste")
			(net "GB_VDDA")
		)
		(pad "N27" smd circle
			(at 10.500106 -3.50012)
			(size 0.4572 0.4572)
			(layers "F.Cu" "F.Mask" "F.Paste")
			(net "PHY_DPB_TO_SCC_C_5_DN")
		)
		(pad "N28" smd circle
			(at 11.500104 -3.50012)
			(size 0.4572 0.4572)
			(layers "F.Cu" "F.Mask" "F.Paste")
			(net "PHY_DPB_TO_SCC_C_5_DP")
		)
		(pad "N29" smd circle
			(at 12.500102 -3.50012)
			(size 0.4572 0.4572)
			(layers "F.Cu" "F.Mask" "F.Paste")
			(net "GND")
		)
		(pad "N30" smd circle
			(at 13.5001 -3.50012)
			(size 0.4572 0.4572)
			(layers "F.Cu" "F.Mask" "F.Paste")
			(net "GB_VDDA")
		)
		(pad "N31" smd circle
			(at 14.500098 -3.50012)
			(size 0.4572 0.4572)
			(layers "F.Cu" "F.Mask" "F.Paste")
			(net "PHY_SCC_TO_DPB_5_DN")
		)
		(pad "N32" smd circle
			(at 15.500096 -3.50012)
			(size 0.4572 0.4572)
			(layers "F.Cu" "F.Mask" "F.Paste")
			(net "PHY_SCC_TO_DPB_5_DP")
		)
		(pad "P1" smd circle
			(at -15.500096 -2.500122)
			(size 0.4572 0.4572)
			(layers "F.Cu" "F.Mask" "F.Paste")
			(net "Net_1264")
		)
		(pad "P2" smd circle
			(at -14.500098 -2.500122)
			(size 0.4572 0.4572)
			(layers "F.Cu" "F.Mask" "F.Paste")
			(net "VDDIO_DDR")
		)
		(pad "P3" smd circle
			(at -13.5001 -2.500122)
			(size 0.4572 0.4572)
			(layers "F.Cu" "F.Mask" "F.Paste")
			(net "Net_1263")
		)
		(pad "P4" smd circle
			(at -12.500102 -2.500122)
			(size 0.4572 0.4572)
			(layers "F.Cu" "F.Mask" "F.Paste")
			(net "VDDIO_DDR")
		)
		(pad "P5" smd circle
			(at -11.500104 -2.500122)
			(size 0.4572 0.4572)
			(layers "F.Cu" "F.Mask" "F.Paste")
			(net "Net_1262")
		)
		(pad "P6" smd circle
			(at -10.500106 -2.500122)
			(size 0.4572 0.4572)
			(layers "F.Cu" "F.Mask" "F.Paste")
			(net "GND")
		)
		(pad "P7" smd circle
			(at -9.500108 -2.500122)
			(size 0.4572 0.4572)
			(layers "F.Cu" "F.Mask" "F.Paste")
			(net "Net_1227")
		)
		(pad "P8" smd circle
			(at -8.50011 -2.500122)
			(size 0.4572 0.4572)
			(layers "F.Cu" "F.Mask" "F.Paste")
			(net "GND")
		)
		(pad "P9" smd circle
			(at -7.500112 -2.500122)
			(size 0.4572 0.4572)
			(layers "F.Cu" "F.Mask" "F.Paste")
			(net "VDDIO_DDR")
		)
		(pad "P10" smd circle
			(at -6.500114 -2.500122)
			(size 0.4572 0.4572)
			(layers "F.Cu" "F.Mask" "F.Paste")
			(net "GND")
		)
		(pad "P11" smd circle
			(at -5.500116 -2.500122)
			(size 0.4572 0.4572)
			(layers "F.Cu" "F.Mask" "F.Paste")
			(net "VDDIO_DDR")
		)
		(pad "P12" smd circle
			(at -4.500118 -2.500122)
			(size 0.4572 0.4572)
			(layers "F.Cu" "F.Mask" "F.Paste")
			(net "GND")
		)
		(pad "P13" smd circle
			(at -3.50012 -2.500122)
			(size 0.4572 0.4572)
			(layers "F.Cu" "F.Mask" "F.Paste")
			(net "P0V9")
		)
		(pad "P14" smd circle
			(at -2.500122 -2.500122)
			(size 0.4572 0.4572)
			(layers "F.Cu" "F.Mask" "F.Paste")
			(net "GND")
		)
		(pad "P15" smd circle
			(at -1.500124 -2.500122)
			(size 0.4572 0.4572)
			(layers "F.Cu" "F.Mask" "F.Paste")
			(net "P0V9")
		)
		(pad "P16" smd circle
			(at -0.500126 -2.500122)
			(size 0.4572 0.4572)
			(layers "F.Cu" "F.Mask" "F.Paste")
			(net "GND")
		)
		(pad "P17" smd circle
			(at 0.500126 -2.500122)
			(size 0.4572 0.4572)
			(layers "F.Cu" "F.Mask" "F.Paste")
			(net "P0V9")
		)
		(pad "P18" smd circle
			(at 1.500124 -2.500122)
			(size 0.4572 0.4572)
			(layers "F.Cu" "F.Mask" "F.Paste")
			(net "GND")
		)
		(pad "P19" smd circle
			(at 2.500122 -2.500122)
			(size 0.4572 0.4572)
			(layers "F.Cu" "F.Mask" "F.Paste")
			(net "P0V9")
		)
		(pad "P20" smd circle
			(at 3.50012 -2.500122)
			(size 0.4572 0.4572)
			(layers "F.Cu" "F.Mask" "F.Paste")
			(net "GND")
		)
		(pad "P21" smd circle
			(at 4.500118 -2.500122)
			(size 0.4572 0.4572)
			(layers "F.Cu" "F.Mask" "F.Paste")
			(net "GND")
		)
		(pad "P22" smd circle
			(at 5.500116 -2.500122)
			(size 0.4572 0.4572)
			(layers "F.Cu" "F.Mask" "F.Paste")
			(net "GB_VDDH")
		)
	)
)
